(kicad_pcb
	(version 20241229)
	(generator "pcbnew")
	(generator_version "9.0")
	(general
		(thickness 1.59)
		(legacy_teardrops no)
	)
	(paper "A3")
	(title_block
		(title "usb-c-power-adapter")
		(date "2025-06-24")
		(rev "1.1.2")
		(company "Antmicro")
		(comment 9 "footprints 114-118 of 122")
	)
	(layers
		(0 "F.Cu" signal)
		(4 "In1.Cu" signal)
		(6 "In2.Cu" signal)
		(2 "B.Cu" signal)
		(9 "F.Adhes" user "F.Adhesive")
		(11 "B.Adhes" user "B.Adhesive")
		(13 "F.Paste" user)
		(15 "B.Paste" user)
		(5 "F.SilkS" user "F.Silkscreen")
		(7 "B.SilkS" user "B.Silkscreen")
		(1 "F.Mask" user)
		(3 "B.Mask" user)
		(17 "Dwgs.User" user "User.Drawings")
		(19 "Cmts.User" user "User.Comments")
		(21 "Eco1.User" user "User.Eco1")
		(23 "Eco2.User" user "User.Eco2")
		(25 "Edge.Cuts" user)
		(27 "Margin" user)
		(31 "F.CrtYd" user "F.Courtyard")
		(29 "B.CrtYd" user "B.Courtyard")
		(35 "F.Fab" user)
		(33 "B.Fab" user)
	)
	(footprint "antmicro-footprints:R_0402_1005Metric"
		(layer "B.Cu")
		(at 88.575 82.9 -90)
		(descr "Resistor SMD 0402")
		(tags "resistor SMD 0402")
		(property "Reference" "R27"
			(at -1.0612 -2.39 90)
			(layer "B.SilkS")
			(effects
				(font
					(size 0.7 0.7)
					(thickness 0.15)
				)
				(justify left bottom mirror)
			)
		)
		(property "Value" "R_1k_0402"
			(at -1.011843 -1.772047 90)
			(layer "B.Fab")
			(effects
				(font
					(size 0.7 0.7)
					(thickness 0.15)
				)
				(justify left bottom mirror)
			)
		)
		(property "Datasheet" "https://www.bourns.com/docs/product-datasheets/cr.pdf"
			(at 0 0 270)
			(layer "F.Fab")
			(hide yes)
			(effects
				(font
					(size 1.27 1.27)
					(thickness 0.15)
				)
			)
		)
		(property "Description" "SMD Chip Resistor, 1 kohm, ± 1%, 63 mW, 0402 [1005 Metric], Thick Film, General Purpose"
			(at 0 0 270)
			(layer "F.Fab")
			(hide yes)
			(effects
				(font
					(size 1.27 1.27)
					(thickness 0.15)
				)
			)
		)
		(property "MPN" "CR0402-FX-1001GLF"
			(at 0 0 270)
			(unlocked yes)
			(layer "B.Fab")
			(hide yes)
			(effects
				(font
					(size 1 1)
					(thickness 0.15)
				)
				(justify mirror)
			)
		)
		(property "Manufacturer" "Bourns"
			(at 0 0 270)
			(unlocked yes)
			(layer "B.Fab")
			(hide yes)
			(effects
				(font
					(size 1 1)
					(thickness 0.15)
				)
				(justify mirror)
			)
		)
		(property "License" "Apache-2.0"
			(at 0 0 270)
			(unlocked yes)
			(layer "B.Fab")
			(hide yes)
			(effects
				(font
					(size 1 1)
					(thickness 0.15)
				)
				(justify mirror)
			)
		)
		(property "Author" "Antmicro"
			(at 0 0 270)
			(unlocked yes)
			(layer "B.Fab")
			(hide yes)
			(effects
				(font
					(size 1 1)
					(thickness 0.15)
				)
				(justify mirror)
			)
		)
		(property "Val" "1k"
			(at 0 0 270)
			(unlocked yes)
			(layer "B.Fab")
			(hide yes)
			(effects
				(font
					(size 1 1)
					(thickness 0.15)
				)
				(justify mirror)
			)
		)
		(property "Tolerance" "1%"
			(at 0 0 270)
			(unlocked yes)
			(layer "B.Fab")
			(hide yes)
			(effects
				(font
					(size 1 1)
					(thickness 0.15)
				)
				(justify mirror)
			)
		)
		(sheetname "/DC-DC Converters/")
		(sheetfile "dc-dc_converters.kicad_sch")
		(attr smd)
		(fp_rect
			(start -0.925 0.47)
			(end 0.925 -0.47)
			(stroke
				(width 0.05)
				(type default)
			)
			(fill no)
			(layer "B.CrtYd")
		)
		(fp_rect
			(start -0.5 0.25)
			(end 0.5 -0.25)
			(stroke
				(width 0.15)
				(type solid)
			)
			(fill no)
			(layer "B.Fab")
		)
		(pad "1" smd roundrect
			(at -0.48 0 270)
			(size 0.59 0.64)
			(layers "B.Cu" "B.Mask" "B.Paste")
			(roundrect_rratio 0.25)
			(net 2 "GND")
			(pintype "passive")
		)
		(pad "2" smd roundrect
			(at 0.48 0 270)
			(size 0.59 0.64)
			(layers "B.Cu" "B.Mask" "B.Paste")
			(roundrect_rratio 0.25)
			(net 39 "Net-(U4-FB)")
			(pintype "passive")
		)
	)
	(footprint "antmicro-footprints:SOT-563"
		(layer "B.Cu")
		(at 85.801 88.9)
		(property "Reference" "U3"
			(at 3.199 2.075 0)
			(layer "B.SilkS")
			(effects
				(font
					(size 0.7 0.7)
					(thickness 0.15)
				)
				(justify right bottom mirror)
			)
		)
		(property "Value" "AP62301Z6-7"
			(at 0 -2 0)
			(layer "B.Fab")
			(effects
				(font
					(size 0.7 0.7)
					(thickness 0.15)
				)
				(justify right bottom mirror)
			)
		)
		(property "Datasheet" "https://www.diodes.com/assets/Datasheets/AP62300_AP62301_AP62300T.pdf"
			(at 0 0 0)
			(layer "F.Fab")
			(hide yes)
			(effects
				(font
					(size 1.27 1.27)
					(thickness 0.15)
				)
			)
		)
		(property "Description" "DC-DC Switching Synchronous Buck Regulator, Adjustable, 4.2V-18Vin, 0.8V-7V/3A out, SOT-563-6"
			(at 0 0 0)
			(layer "F.Fab")
			(hide yes)
			(effects
				(font
					(size 1.27 1.27)
					(thickness 0.15)
				)
			)
		)
		(property "MPN" "AP62301Z6-7"
			(at 0 0 0)
			(unlocked yes)
			(layer "B.Fab")
			(hide yes)
			(effects
				(font
					(size 1 1)
					(thickness 0.15)
				)
				(justify mirror)
			)
		)
		(property "Manufacturer" "Diodes Incorporated"
			(at 0 0 0)
			(unlocked yes)
			(layer "B.Fab")
			(hide yes)
			(effects
				(font
					(size 1 1)
					(thickness 0.15)
				)
				(justify mirror)
			)
		)
		(property "Author" "Antmicro"
			(at 0 0 0)
			(unlocked yes)
			(layer "B.Fab")
			(hide yes)
			(effects
				(font
					(size 1 1)
					(thickness 0.15)
				)
				(justify mirror)
			)
		)
		(property "License" "Apache-2.0"
			(at 0 0 0)
			(unlocked yes)
			(layer "B.Fab")
			(hide yes)
			(effects
				(font
					(size 1 1)
					(thickness 0.15)
				)
				(justify mirror)
			)
		)
		(sheetname "/DC-DC Converters/")
		(sheetfile "dc-dc_converters.kicad_sch")
		(attr smd)
		(fp_line
			(start -0.778 -0.949)
			(end -0.778 -0.776)
			(stroke
				(width 0.15)
				(type solid)
			)
			(layer "B.SilkS")
		)
		(fp_line
			(start -0.724 0.778)
			(end -0.499 0.974)
			(stroke
				(width 0.15)
				(type solid)
			)
			(layer "B.SilkS")
		)
		(fp_line
			(start -0.424 -0.949)
			(end -0.778 -0.949)
			(stroke
				(width 0.15)
				(type solid)
			)
			(layer "B.SilkS")
		)
		(fp_line
			(start 0.526 -0.972)
			(end 0.776 -0.972)
			(stroke
				(width 0.15)
				(type solid)
			)
			(layer "B.SilkS")
		)
		(fp_line
			(start 0.526 0.974)
			(end 0.776 0.974)
			(stroke
				(width 0.15)
				(type solid)
			)
			(layer "B.SilkS")
		)
		(fp_line
			(start 0.776 -0.972)
			(end 0.776 -0.776)
			(stroke
				(width 0.15)
				(type solid)
			)
			(layer "B.SilkS")
		)
		(fp_line
			(start 0.776 0.778)
			(end 0.776 0.974)
			(stroke
				(width 0.15)
				(type solid)
			)
			(layer "B.SilkS")
		)
		(fp_circle
			(center -0.903 0.999)
			(end -0.952 0.95)
			(stroke
				(width 0.15)
				(type solid)
			)
			(fill yes)
			(layer "B.SilkS")
		)
		(fp_rect
			(start 1.19 1.12)
			(end -1.2 -1.1)
			(stroke
				(width 0.05)
				(type solid)
			)
			(fill no)
			(layer "B.CrtYd")
		)
		(fp_line
			(start -0.653 -0.847)
			(end -0.653 0.678)
			(stroke
				(width 0.15)
				(type solid)
			)
			(layer "B.Fab")
		)
		(fp_line
			(start -0.653 -0.847)
			(end 0.651 -0.847)
			(stroke
				(width 0.15)
				(type solid)
			)
			(layer "B.Fab")
		)
		(fp_line
			(start -0.653 0.678)
			(end -0.453 0.849)
			(stroke
				(width 0.15)
				(type solid)
			)
			(layer "B.Fab")
		)
		(fp_line
			(start 0.651 -0.847)
			(end 0.651 0.849)
			(stroke
				(width 0.15)
				(type solid)
			)
			(layer "B.Fab")
		)
		(fp_line
			(start 0.651 0.849)
			(end -0.453 0.849)
			(stroke
				(width 0.15)
				(type solid)
			)
			(layer "B.Fab")
		)
		(pad "1" smd roundrect
			(at -0.749 0.499 90)
			(size 0.3 0.6)
			(layers "B.Cu" "B.Mask" "B.Paste")
			(roundrect_rratio 0.25)
			(net 5 "+12V")
			(pinfunction "V_{IN}")
			(pintype "power_in")
		)
		(pad "2" smd roundrect
			(at -0.749 -0.001 90)
			(size 0.3 0.6)
			(layers "B.Cu" "B.Mask" "B.Paste")
			(roundrect_rratio 0.25)
			(net 21 "Net-(U3-SW)")
			(pinfunction "SW")
			(pintype "power_out")
		)
		(pad "3" smd roundrect
			(at -0.749 -0.497 90)
			(size 0.3 0.6)
			(layers "B.Cu" "B.Mask" "B.Paste")
			(roundrect_rratio 0.25)
			(net 2 "GND")
			(pinfunction "GND")
			(pintype "power_in")
		)
		(pad "4" smd roundrect
			(at 0.747 -0.497 90)
			(size 0.3 0.6)
			(layers "B.Cu" "B.Mask" "B.Paste")
			(roundrect_rratio 0.25)
			(net 22 "Net-(U3-BST)")
			(pinfunction "BST")
			(pintype "output")
		)
		(pad "5" smd roundrect
			(at 0.747 -0.001 90)
			(size 0.3 0.6)
			(layers "B.Cu" "B.Mask" "B.Paste")
			(roundrect_rratio 0.25)
			(net 47 "Net-(U3-EN)")
			(pinfunction "EN")
			(pintype "input")
		)
		(pad "6" smd roundrect
			(at 0.747 0.499 90)
			(size 0.3 0.6)
			(layers "B.Cu" "B.Mask" "B.Paste")
			(roundrect_rratio 0.25)
			(net 40 "Net-(U3-FB)")
			(pinfunction "FB")
			(pintype "input")
		)
	)
	(footprint "antmicro-footprints:C_1206_3216Metric"
		(layer "B.Cu")
		(at 95.8 97.85 90)
		(descr "Capacitor SMD 1206")
		(tags "capacitor SMD 1206")
		(property "Reference" "C20"
			(at 25.968 -9.438 0)
			(layer "B.SilkS")
			(effects
				(font
					(size 0.7 0.7)
					(thickness 0.15)
				)
				(justify left bottom mirror)
			)
		)
		(property "Value" "C_47u_25V_1206"
			(at 0 -2.101 90)
			(layer "B.Fab")
			(effects
				(font
					(size 0.7 0.7)
					(thickness 0.15)
				)
				(justify right bottom mirror)
			)
		)
		(property "Datasheet" "https://product.tdk.com/en/search/capacitor/ceramic/mlcc/info?part_no=C3216X5R1E476M160AC"
			(at 0 0 90)
			(layer "F.Fab")
			(hide yes)
			(effects
				(font
					(size 1.27 1.27)
					(thickness 0.15)
				)
			)
		)
		(property "Description" "SMD Multilayer Ceramic Capacitor, 47 µF, 25 V, 1206 [3216 Metric], ± 20%, X5R"
			(at 0 0 90)
			(layer "F.Fab")
			(hide yes)
			(effects
				(font
					(size 1.27 1.27)
					(thickness 0.15)
				)
			)
		)
		(property "MPN" "C3216X5R1E476M160AC"
			(at 0 0 90)
			(unlocked yes)
			(layer "B.Fab")
			(hide yes)
			(effects
				(font
					(size 1 1)
					(thickness 0.15)
				)
				(justify mirror)
			)
		)
		(property "Val" "47u"
			(at 0 0 90)
			(unlocked yes)
			(layer "B.Fab")
			(hide yes)
			(effects
				(font
					(size 1 1)
					(thickness 0.15)
				)
				(justify mirror)
			)
		)
		(property "Voltage" "25V"
			(at 0 0 90)
			(unlocked yes)
			(layer "B.Fab")
			(hide yes)
			(effects
				(font
					(size 1 1)
					(thickness 0.15)
				)
				(justify mirror)
			)
		)
		(property "Author" "Antmicro"
			(at 0 0 90)
			(unlocked yes)
			(layer "B.Fab")
			(hide yes)
			(effects
				(font
					(size 1 1)
					(thickness 0.15)
				)
				(justify mirror)
			)
		)
		(property "License" "Apache-2.0"
			(at 0 0 90)
			(unlocked yes)
			(layer "B.Fab")
			(hide yes)
			(effects
				(font
					(size 1 1)
					(thickness 0.15)
				)
				(justify mirror)
			)
		)
		(property "Manufacturer" "TDK"
			(at 0 0 90)
			(unlocked yes)
			(layer "B.Fab")
			(hide yes)
			(effects
				(font
					(size 1 1)
					(thickness 0.15)
				)
				(justify mirror)
			)
		)
		(property "Dielectric" "X5R"
			(at 0 0 90)
			(unlocked yes)
			(layer "B.Fab")
			(hide yes)
			(effects
				(font
					(size 1 1)
					(thickness 0.15)
				)
				(justify mirror)
			)
		)
		(property "Public" "False"
			(at 0 0 90)
			(unlocked yes)
			(layer "B.Fab")
			(hide yes)
			(effects
				(font
					(size 1 1)
					(thickness 0.15)
				)
				(justify mirror)
			)
		)
		(sheetname "/DC-DC Converters/")
		(sheetfile "dc-dc_converters.kicad_sch")
		(attr smd)
		(fp_line
			(start -0.8 -0.901)
			(end 0.8 -0.901)
			(stroke
				(width 0.15)
				(type solid)
			)
			(layer "B.SilkS")
		)
		(fp_line
			(start -0.8 0.899)
			(end 0.8 0.899)
			(stroke
				(width 0.15)
				(type solid)
			)
			(layer "B.SilkS")
		)
		(fp_rect
			(start -2.325 1.15)
			(end 2.325 -1.15)
			(stroke
				(width 0.05)
				(type default)
			)
			(fill no)
			(layer "B.CrtYd")
		)
		(fp_rect
			(start -1.6 0.799)
			(end 1.6 -0.801)
			(stroke
				(width 0.15)
				(type solid)
			)
			(fill no)
			(layer "B.Fab")
		)
		(pad "1" smd roundrect
			(at -1.5 -0.001 90)
			(size 1.15 1.8)
			(layers "B.Cu" "B.Mask" "B.Paste")
			(roundrect_rratio 0.25)
			(net 2 "GND")
			(pintype "passive")
		)
		(pad "2" smd roundrect
			(at 1.5 -0.001 90)
			(size 1.15 1.8)
			(layers "B.Cu" "B.Mask" "B.Paste")
			(roundrect_rratio 0.25)
			(net 5 "+12V")
			(pintype "passive")
		)
	)
	(footprint "antmicro-footprints:C_0603_1608Metric"
		(layer "B.Cu")
		(at 82.55 82.8 90)
		(descr "Capacitor SMD 0603")
		(tags "capacitor 0603")
		(property "Reference" "C26"
			(at 6.473 0.211 270)
			(layer "B.SilkS")
			(effects
				(font
					(size 0.7 0.7)
					(thickness 0.15)
				)
				(justify left bottom mirror)
			)
		)
		(property "Value" "C_10u_25V_0603"
			(at -1.42757 -1.770288 90)
			(layer "B.Fab")
			(effects
				(font
					(size 0.7 0.7)
					(thickness 0.15)
				)
				(justify right bottom mirror)
			)
		)
		(property "Datasheet" "https://product.tdk.com/en/search/capacitor/ceramic/mlcc/info?part_no=C1608X5R1E106M080AC"
			(at 0 0 90)
			(layer "F.Fab")
			(hide yes)
			(effects
				(font
					(size 1.27 1.27)
					(thickness 0.15)
				)
			)
		)
		(property "Description" "SMD Multilayer Ceramic Capacitor, 10 µF, 25 V, 0603 [1608 Metric], ± 20%, X5R, C"
			(at 0 0 90)
			(layer "F.Fab")
			(hide yes)
			(effects
				(font
					(size 1.27 1.27)
					(thickness 0.15)
				)
			)
		)
		(property "MPN" "C1608X5R1E106M080AC"
			(at 0 0 90)
			(unlocked yes)
			(layer "B.Fab")
			(hide yes)
			(effects
				(font
					(size 1 1)
					(thickness 0.15)
				)
				(justify mirror)
			)
		)
		(property "Manufacturer" "TDK"
			(at 0 0 90)
			(unlocked yes)
			(layer "B.Fab")
			(hide yes)
			(effects
				(font
					(size 1 1)
					(thickness 0.15)
				)
				(justify mirror)
			)
		)
		(property "License" "Apache-2.0"
			(at 0 0 90)
			(unlocked yes)
			(layer "B.Fab")
			(hide yes)
			(effects
				(font
					(size 1 1)
					(thickness 0.15)
				)
				(justify mirror)
			)
		)
		(property "Author" "Antmicro"
			(at 0 0 90)
			(unlocked yes)
			(layer "B.Fab")
			(hide yes)
			(effects
				(font
					(size 1 1)
					(thickness 0.15)
				)
				(justify mirror)
			)
		)
		(property "Val" "10u"
			(at 0 0 90)
			(unlocked yes)
			(layer "B.Fab")
			(hide yes)
			(effects
				(font
					(size 1 1)
					(thickness 0.15)
				)
				(justify mirror)
			)
		)
		(property "Voltage" "25V"
			(at 0 0 90)
			(unlocked yes)
			(layer "B.Fab")
			(hide yes)
			(effects
				(font
					(size 1 1)
					(thickness 0.15)
				)
				(justify mirror)
			)
		)
		(property "Dielectric" ""
			(at 0 0 90)
			(unlocked yes)
			(layer "B.Fab")
			(hide yes)
			(effects
				(font
					(size 1 1)
					(thickness 0.15)
				)
				(justify mirror)
			)
		)
		(sheetname "/DC-DC Converters/")
		(sheetfile "dc-dc_converters.kicad_sch")
		(attr smd)
		(fp_line
			(start 0.15 -0.4)
			(end -0.15 -0.4)
			(stroke
				(width 0.15)
				(type solid)
			)
			(layer "B.SilkS")
		)
		(fp_line
			(start 0.15 0.4)
			(end -0.15 0.4)
			(stroke
				(width 0.15)
				(type solid)
			)
			(layer "B.SilkS")
		)
		(fp_rect
			(start -1.25 0.65)
			(end 1.25 -0.65)
			(stroke
				(width 0.05)
				(type solid)
			)
			(fill no)
			(layer "B.CrtYd")
		)
		(fp_rect
			(start -0.8 0.4)
			(end 0.8 -0.4)
			(stroke
				(width 0.15)
				(type solid)
			)
			(fill no)
			(layer "B.Fab")
		)
		(pad "1" smd roundrect
			(at -0.7 0 90)
			(size 0.8 1)
			(layers "B.Cu" "B.Mask" "B.Paste")
			(roundrect_rratio 0.2)
			(net 2 "GND")
			(pintype "passive")
		)
		(pad "2" smd roundrect
			(at 0.7 0 90)
			(size 0.8 1)
			(layers "B.Cu" "B.Mask" "B.Paste")
			(roundrect_rratio 0.2)
			(net 1 "+3V3")
			(pintype "passive")
		)
	)
	(footprint "antmicro-footprints:R_0402_1005Metric"
		(layer "B.Cu")
		(at 87.4 80.5 -90)
		(descr "Resistor SMD 0402")
		(tags "resistor SMD 0402")
		(property "Reference" "R24"
			(at -3.157 -0.484 90)
			(layer "B.SilkS")
			(effects
				(font
					(size 0.7 0.7)
					(thickness 0.15)
				)
				(justify left bottom mirror)
			)
		)
		(property "Value" "R_15k_0402"
			(at -1.011843 -1.772047 90)
			(layer "B.Fab")
			(effects
				(font
					(size 0.7 0.7)
					(thickness 0.15)
				)
				(justify left bottom mirror)
			)
		)
		(property "Datasheet" "https://www.bourns.com/docs/product-datasheets/cr.pdf"
			(at 0 0 270)
			(layer "F.Fab")
			(hide yes)
			(effects
				(font
					(size 1.27 1.27)
					(thickness 0.15)
				)
			)
		)
		(property "Description" "SMD Chip Resistor, 15 kohm, ± 1%, 62.5 mW, 0402 [1005 Metric], Thick Film, General Purpose"
			(at 0 0 270)
			(layer "F.Fab")
			(hide yes)
			(effects
				(font
					(size 1.27 1.27)
					(thickness 0.15)
				)
			)
		)
		(property "MPN" "CR0402-FX-1502GLF"
			(at 0 0 270)
			(unlocked yes)
			(layer "B.Fab")
			(hide yes)
			(effects
				(font
					(size 1 1)
					(thickness 0.15)
				)
				(justify mirror)
			)
		)
		(property "Manufacturer" "Bourns"
			(at 0 0 270)
			(unlocked yes)
			(layer "B.Fab")
			(hide yes)
			(effects
				(font
					(size 1 1)
					(thickness 0.15)
				)
				(justify mirror)
			)
		)
		(property "License" "Apache-2.0"
			(at 0 0 270)
			(unlocked yes)
			(layer "B.Fab")
			(hide yes)
			(effects
				(font
					(size 1 1)
					(thickness 0.15)
				)
				(justify mirror)
			)
		)
		(property "Author" "Antmicro"
			(at 0 0 270)
			(unlocked yes)
			(layer "B.Fab")
			(hide yes)
			(effects
				(font
					(size 1 1)
					(thickness 0.15)
				)
				(justify mirror)
			)
		)
		(property "Val" "15k"
			(at 0 0 270)
			(unlocked yes)
			(layer "B.Fab")
			(hide yes)
			(effects
				(font
					(size 1 1)
					(thickness 0.15)
				)
				(justify mirror)
			)
		)
		(property "Tolerance" "1%"
			(at 0 0 270)
			(unlocked yes)
			(layer "B.Fab")
			(hide yes)
			(effects
				(font
					(size 1 1)
					(thickness 0.15)
				)
				(justify mirror)
			)
		)
		(sheetname "/DC-DC Converters/")
		(sheetfile "dc-dc_converters.kicad_sch")
		(attr smd)
		(fp_rect
			(start -0.925 0.47)
			(end 0.925 -0.47)
			(stroke
				(width 0.05)
				(type default)
			)
			(fill no)
			(layer "B.CrtYd")
		)
		(fp_rect
			(start -0.5 0.25)
			(end 0.5 -0.25)
			(stroke
				(width 0.15)
				(type solid)
			)
			(fill no)
			(layer "B.Fab")
		)
		(pad "1" smd roundrect
			(at -0.48 0 270)
			(size 0.59 0.64)
			(layers "B.Cu" "B.Mask" "B.Paste")
			(roundrect_rratio 0.25)
			(net 2 "GND")
			(pintype "passive")
		)
		(pad "2" smd roundrect
			(at 0.48 0 270)
			(size 0.59 0.64)
			(layers "B.Cu" "B.Mask" "B.Paste")
			(roundrect_rratio 0.25)
			(net 9 "Net-(U4-EN)")
			(pintype "passive")
		)
	)
)
